# T6G (Grand Teton) — schematic netlist excerpt (pin names and nets, part order shuffled) for the footprints in the layout excerpt that follows; sources: Cadence DE-HDL packaged netlist, KiCad conversion of 04192023_DAF0TMB3IC0_F0TG_MB_C_brd_V02_OCP.brd

R181  Q_RES  0 5% CHIP  pkg 0402LF  page 82 : A = CPU0_SP5R2 ; B = FM_CPU0_SP5R2
R8385  Q_RES  0 5% CHIP  pkg 0402LF  page 224 : A = PWRGD_PVDD11_S3_P1 ; B = PWRGD_PVDD11_S3_P1_R

(kicad_pcb
	(version 20260206)
	(generator "pcbnew")
	(generator_version "10.0")
	(general
		(thickness 1.6)
		(legacy_teardrops no)
	)
	(paper "A4")
	(title_block
		(title "04192023_DAF0TMB3IC0_F0TG_MB_C_brd_V02_OCP.brd")
		(comment 1 "Grand Teton / footprints 7743-7744 of 8354")
	)
	(layers
		(0 "F.Cu" signal "TOP")
		(4 "In1.Cu" signal "GND")
		(6 "In2.Cu" signal "IN1")
		(8 "In3.Cu" signal "GND1")
		(10 "In4.Cu" signal "IN2")
		(12 "In5.Cu" signal "GND2")
		(14 "In6.Cu" signal "IN3")
		(16 "In7.Cu" signal "GND3")
		(18 "In8.Cu" signal "VCC")
		(20 "In9.Cu" signal "VCC1")
		(22 "In10.Cu" signal "GND4")
		(24 "In11.Cu" signal "IN4")
		(26 "In12.Cu" signal "GND5")
		(28 "In13.Cu" signal "IN5")
		(30 "In14.Cu" signal "GND6")
		(32 "In15.Cu" signal "IN6")
		(34 "In16.Cu" signal "GND7")
		(2 "B.Cu" signal "BOTTOM")
		(9 "F.Adhes" user "F.Adhesive")
		(11 "B.Adhes" user "B.Adhesive")
		(13 "F.Paste" user "Package Geometry/Pastemask Top")
		(15 "B.Paste" user "Package Geometry/Pastemask Bottom")
		(5 "F.SilkS" user "Ref Des/Silkscreen Top")
		(7 "B.SilkS" user "Ref Des/Silkscreen Bottom")
		(1 "F.Mask" user "Board Geometry/Soldermask Top")
		(3 "B.Mask" user "Board Geometry/Soldermask Bottom")
		(17 "Dwgs.User" user "User.Drawings")
		(19 "Cmts.User" user "User.Comments")
		(21 "Eco1.User" user "User.Eco1")
		(23 "Eco2.User" user "User.Eco2")
		(25 "Edge.Cuts" user "Board Geometry/Outline")
		(27 "Margin" user)
		(31 "F.CrtYd" user "Package Geometry/Place Bound Top")
		(29 "B.CrtYd" user "Package Geometry/Place Bound Bottom")
		(35 "F.Fab" user "Ref Des/Assembly Top")
		(33 "B.Fab" user "Ref Des/Assembly Bottom")
	)
	(footprint ""
		(layer "B.Cu")
		(at 186.817 -100.294948 -90)
		(property "Reference" "R181"
			(at 0 0 90)
			(layer "B.SilkS")
			(hide yes)
			(effects
				(font
					(size 1.27 1.27)
				)
				(justify mirror)
			)
		)
		(property "Value" ""
			(at 0 0 90)
			(layer "B.Fab")
			(effects
				(font
					(size 1.27 1.27)
				)
				(justify mirror)
			)
		)
		(duplicate_pad_numbers_are_jumpers no)
		(fp_line
			(start -0.7874 0.4064)
			(end 0.7874 0.4064)
			(stroke
				(width 0.1524)
				(type default)
			)
			(layer "B.SilkS")
		)
		(fp_line
			(start 0.7874 0.4064)
			(end 0.7874 -0.4064)
			(stroke
				(width 0.1524)
				(type default)
			)
			(layer "B.SilkS")
		)
		(fp_line
			(start -0.7874 -0.4064)
			(end -0.7874 0.4064)
			(stroke
				(width 0.1524)
				(type default)
			)
			(layer "B.SilkS")
		)
		(fp_line
			(start 0.7874 -0.4064)
			(end -0.7874 -0.4064)
			(stroke
				(width 0.1524)
				(type default)
			)
			(layer "B.SilkS")
		)
		(fp_line
			(start -0.67945 0.3048)
			(end -0.120396 0.3048)
			(stroke
				(width 0.1)
				(type default)
			)
			(layer "B.Fab")
		)
		(fp_line
			(start -0.120396 0.3048)
			(end -0.120396 0.2794)
			(stroke
				(width 0.1)
				(type default)
			)
			(layer "B.Fab")
		)
		(fp_line
			(start 0.12065 0.3048)
			(end 0.67945 0.3048)
			(stroke
				(width 0.1)
				(type default)
			)
			(layer "B.Fab")
		)
		(fp_line
			(start 0.67945 0.3048)
			(end 0.67945 -0.305054)
			(stroke
				(width 0.1)
				(type default)
			)
			(layer "B.Fab")
		)
		(fp_line
			(start -0.120396 0.2794)
			(end 0.12065 0.2794)
			(stroke
				(width 0.1)
				(type default)
			)
			(layer "B.Fab")
		)
		(fp_line
			(start 0.12065 0.2794)
			(end 0.12065 0.3048)
			(stroke
				(width 0.1)
				(type default)
			)
			(layer "B.Fab")
		)
		(fp_line
			(start -0.12065 -0.2794)
			(end -0.12065 -0.3048)
			(stroke
				(width 0.1)
				(type default)
			)
			(layer "B.Fab")
		)
		(fp_line
			(start 0.12065 -0.2794)
			(end -0.12065 -0.2794)
			(stroke
				(width 0.1)
				(type default)
			)
			(layer "B.Fab")
		)
		(fp_line
			(start -0.67945 -0.3048)
			(end -0.67945 0.3048)
			(stroke
				(width 0.1)
				(type default)
			)
			(layer "B.Fab")
		)
		(fp_line
			(start -0.12065 -0.3048)
			(end -0.67945 -0.3048)
			(stroke
				(width 0.1)
				(type default)
			)
			(layer "B.Fab")
		)
		(fp_line
			(start 0.12065 -0.305054)
			(end 0.12065 -0.2794)
			(stroke
				(width 0.1)
				(type default)
			)
			(layer "B.Fab")
		)
		(fp_line
			(start 0.67945 -0.305054)
			(end 0.12065 -0.305054)
			(stroke
				(width 0.1)
				(type default)
			)
			(layer "B.Fab")
		)
		(pad "1" smd circle
			(at 0.40005 0 90)
			(size 0 0)
			(layers "B.Cu" "B.Mask" "B.Paste")
			(net "CPU0_SP5R2")
		)
		(pad "2" smd circle
			(at -0.40005 0 90)
			(size 0 0)
			(layers "B.Cu" "B.Mask" "B.Paste")
			(net "FM_CPU0_SP5R2")
		)
	)
	(footprint ""
		(layer "B.Cu")
		(at 158.39948 -352.566478 180)
		(property "Reference" "R8385"
			(at 0 0 0)
			(layer "B.SilkS")
			(hide yes)
			(effects
				(font
					(size 1.27 1.27)
				)
				(justify mirror)
			)
		)
		(property "Value" ""
			(at 0 0 0)
			(layer "B.Fab")
			(effects
				(font
					(size 1.27 1.27)
				)
				(justify mirror)
			)
		)
		(duplicate_pad_numbers_are_jumpers no)
		(fp_line
			(start 0.7874 0.4064)
			(end 0.7874 -0.4064)
			(stroke
				(width 0.1524)
				(type default)
			)
			(layer "B.SilkS")
		)
		(fp_line
			(start 0.7874 -0.4064)
			(end -0.7874 -0.4064)
			(stroke
				(width 0.1524)
				(type default)
			)
			(layer "B.SilkS")
		)
		(fp_line
			(start -0.7874 0.4064)
			(end 0.7874 0.4064)
			(stroke
				(width 0.1524)
				(type default)
			)
			(layer "B.SilkS")
		)
		(fp_line
			(start -0.7874 -0.4064)
			(end -0.7874 0.4064)
			(stroke
				(width 0.1524)
				(type default)
			)
			(layer "B.SilkS")
		)
		(fp_line
			(start 0.67945 0.3048)
			(end 0.67945 -0.305054)
			(stroke
				(width 0.1)
				(type default)
			)
			(layer "B.Fab")
		)
		(fp_line
			(start 0.67945 -0.305054)
			(end 0.12065 -0.305054)
			(stroke
				(width 0.1)
				(type default)
			)
			(layer "B.Fab")
		)
		(fp_line
			(start 0.12065 0.3048)
			(end 0.67945 0.3048)
			(stroke
				(width 0.1)
				(type default)
			)
			(layer "B.Fab")
		)
		(fp_line
			(start 0.12065 0.2794)
			(end 0.12065 0.3048)
			(stroke
				(width 0.1)
				(type default)
			)
			(layer "B.Fab")
		)
		(fp_line
			(start 0.12065 -0.2794)
			(end -0.12065 -0.2794)
			(stroke
				(width 0.1)
				(type default)
			)
			(layer "B.Fab")
		)
		(fp_line
			(start 0.12065 -0.305054)
			(end 0.12065 -0.2794)
			(stroke
				(width 0.1)
				(type default)
			)
			(layer "B.Fab")
		)
		(fp_line
			(start -0.120396 0.3048)
			(end -0.120396 0.2794)
			(stroke
				(width 0.1)
				(type default)
			)
			(layer "B.Fab")
		)
		(fp_line
			(start -0.120396 0.2794)
			(end 0.12065 0.2794)
			(stroke
				(width 0.1)
				(type default)
			)
			(layer "B.Fab")
		)
		(fp_line
			(start -0.12065 -0.2794)
			(end -0.12065 -0.3048)
			(stroke
				(width 0.1)
				(type default)
			)
			(layer "B.Fab")
		)
		(fp_line
			(start -0.12065 -0.3048)
			(end -0.67945 -0.3048)
			(stroke
				(width 0.1)
				(type default)
			)
			(layer "B.Fab")
		)
		(fp_line
			(start -0.67945 0.3048)
			(end -0.120396 0.3048)
			(stroke
				(width 0.1)
				(type default)
			)
			(layer "B.Fab")
		)
		(fp_line
			(start -0.67945 -0.3048)
			(end -0.67945 0.3048)
			(stroke
				(width 0.1)
				(type default)
			)
			(layer "B.Fab")
		)
		(pad "1" smd circle
			(at 0.40005 0)
			(size 0 0)
			(layers "B.Cu" "B.Mask" "B.Paste")
			(net "PWRGD_PVDD11_S3_P1")
		)
		(pad "2" smd circle
			(at -0.40005 0)
			(size 0 0)
			(layers "B.Cu" "B.Mask" "B.Paste")
			(net "PWRGD_PVDD11_S3_P1_R")
		)
	)
)
